FILE_TYPE = CONNECTIVITY;
{Allegro Design Entry HDL 17.2-2016 S081 (4005846) 1/11/2022}
"PAGE_NUMBER" = 132;
0"NC";
1"P3V3_AUX\g";
2"P3V3_OCP_V3_2\g";
3"P3V3_AUX\g";
4"P3V3_AUX\g";
5"P3V3_AUX\g";
6"P3V3_AUX\g";
7"P3V3_AUX\g";
8"P3V3_AUX\g";
9"P3V3_AUX\g";
10"P3V3_AUX\g";
11"P3V3_AUX\g";
12"GND\g";
13"GND\g";
14"GND\g";
15"GND\g";
16"GND\g";
17"GND\g";
18"GND\g";
19"GND\g";
20"GND\g";
21"GND\g";
22"GND\g";
23"GND\g";
24"GND\g";
25"GND\g";
26"GND\g";
27"GND\g";
28"HP_LVC3_OCP_V3_2_PWRGD"$PHYS_NET_NAME"RST_PCIE_M2_N"CDS_PHYS_NET_NAME"HP_LVC3_OCP_V3_2_PWRGD";
29"HP_OCP_V3_2_RST_R"$PHYS_NET_NAME"RST_PCIE_M2_N"CDS_PHYS_NET_NAME"HP_OCP_V3_1_RST_R";
30"TP_PCA9555_U51_P17"$PHYS_NET_NAME"RST_PCIE_M2_N"CDS_PHYS_NET_NAME"TP_PCA9555_0_P17";
31"TP_PCA9555_U51_P16"$PHYS_NET_NAME"RST_PCIE_M2_N"CDS_PHYS_NET_NAME"TP_PCA9555_0_P16";
32"TP_PCA9555_U51_P15"$PHYS_NET_NAME"RST_PCIE_M2_N"CDS_PHYS_NET_NAME"TP_PCA9555_0_P15";
33"TP_PCA9555_U51_P14"$PHYS_NET_NAME"RST_PCIE_M2_N"CDS_PHYS_NET_NAME"TP_PCA9555_0_P14";
34"TP_PCA9555_U51_P13"$PHYS_NET_NAME"RST_PCIE_M2_N"CDS_PHYS_NET_NAME"TP_PCA9555_0_P13";
35"TP_PCA9555_U51_P12"$PHYS_NET_NAME"RST_PCIE_M2_N"CDS_PHYS_NET_NAME"TP_PCA9555_0_P12";
36"TP_PCA9555_U51_P11"$PHYS_NET_NAME"RST_PCIE_M2_N"CDS_PHYS_NET_NAME"TP_PCA9555_0_P11";
37"HP_OCP_V3_2_EN"$PHYS_NET_NAME"RST_PCIE_M2_N"CDS_PHYS_NET_NAME"HP_OCP_V3_1_EN";
38"TP_PCA9555_U51_P00"$PHYS_NET_NAME"RST_PCIE_M2_N"CDS_PHYS_NET_NAME"TP_PCA9555_0_P00";
39"TP_PCA9555_U51_P01"$PHYS_NET_NAME"RST_PCIE_M2_N"CDS_PHYS_NET_NAME"TP_PCA9555_0_P01";
40"HP_LVC3_OCP_V3_2_ATTN_OUT_SW_N"$PHYS_NET_NAME"RST_PCIE_M2_N"CDS_PHYS_NET_NAME"HP_LVC3_OCP_V3_1_ATTN_OUT_SW_N";
41"HP_LVC3_OCP_V3_2_PRSNT2_N"$PHYS_NET_NAME"RST_PCIE_M2_N"CDS_PHYS_NET_NAME"HP_LVC3_OCP_V3_1_PRSNT2_N";
42"HP_LVC3_OCP_V3_2_PWRGD_R2"$PHYS_NET_NAME"RST_PCIE_M2_N"CDS_PHYS_NET_NAME"HP_LVC3_OCP_V3_1_PWRGD_R2";
43"OCP_V3_2_AUX_PWR_PLD_EN_R"$PHYS_NET_NAME"RST_PCIE_M2_N"CDS_PHYS_NET_NAME"OCP_SFF_AUX_PWR_PLD_EN_R";
44"OCP_V3_2_AUX_PWR_EN_R2"$PHYS_NET_NAME"RST_PCIE_M2_N"CDS_PHYS_NET_NAME"OCP_SFF_AUX_PWR_EN_R2";
45"HP_LVC3_OCP_V3_2_PWRGD_R"$PHYS_NET_NAME"RST_PCIE_M2_N"CDS_PHYS_NET_NAME"HP_LVC3_OCP_V3_2_PWRGD";
46"RST_OCP_V3_2_N"$PHYS_NET_NAME"RST_PCIE_M2_N"CDS_PHYS_NET_NAME"RST_OCP_V3_1_N";
47"OCP_V3_2_AUX_PWR_PLD_EN"$PHYS_NET_NAME"RST_PCIE_M2_N"CDS_PHYS_NET_NAME"OCP_SFF_AUX_PWR_PLD_EN";
48"HP_LVC3_OCP_V3_2_PWRGD_R"$PHYS_NET_NAME"RST_PCIE_M2_N"CDS_PHYS_NET_NAME"HP_LVC3_OCP_V3_1_PWRGD_R";
49"RST_HP_OCP_V3_2_N"$PHYS_NET_NAME"RST_PCIE_M2_N"CDS_PHYS_NET_NAME"RST_HP_OCP_V3_1_N";
50"OCP_V3_2_AUX_PWR_EN"$PHYS_NET_NAME"RST_PCIE_M2_N"CDS_PHYS_NET_NAME"OCP_SFF_AUX_PWR_EN";
51"HP_LVC3_OCP_V3_2_PRSNT2_N"$PHYS_NET_NAME"RST_PCIE_M2_N"CDS_PHYS_NET_NAME"HP_LVC3_OCP_V3_1_PRSNT2_N";
52"HP_OCP_V3_2_EN"$PHYS_NET_NAME"RST_PCIE_M2_N"CDS_PHYS_NET_NAME"HP_OCP_V3_1_EN";
53"HP_LVC3_OCP_V3_2_EN"$PHYS_NET_NAME"RST_PCIE_M2_N"CDS_PHYS_NET_NAME"HP_LVC3_OCP_V3_1_EN";
54"HP_LVC3_OCP_V3_2_PRSNT2"$PHYS_NET_NAME"RST_PCIE_M2_N"CDS_PHYS_NET_NAME"HP_LVC3_OCP_V3_1_PRSNT2";
55"SMB_PEHPCPU1_LVC3_SCL"$PHYS_NET_NAME"RST_PCIE_M2_N"CDS_PHYS_NET_NAME"SMB_PEHPCPU0_LVC3_SCL";
56"TP_PCA9555_U51_P10"$PHYS_NET_NAME"RST_PCIE_M2_N"CDS_PHYS_NET_NAME"TP_PCA9555_0_P10";
57"TP_PCA9555_U51_P07"$PHYS_NET_NAME"RST_PCIE_M2_N"CDS_PHYS_NET_NAME"TP_PCA9555_0_P7";
58"TP_PCA9555_U51_P06"$PHYS_NET_NAME"RST_PCIE_M2_N"CDS_PHYS_NET_NAME"TP_PCA9555_0_P6";
59"TP_PCA9555_U51_P05"$PHYS_NET_NAME"RST_PCIE_M2_N"CDS_PHYS_NET_NAME"HP_LVC3_OCP_V3_1_FAULT_N";
60"FM_SMB_CPU1_ALERT"$PHYS_NET_NAME"RST_PCIE_M2_N"CDS_PHYS_NET_NAME"FM_SMB_CPU0_ALERT";
61"PD_SMB_OCP2_HP_ADD2"$PHYS_NET_NAME"RST_PCIE_M2_N"CDS_PHYS_NET_NAME"PD_SMB_OCP1_HP_ADD2";
62"SMB_PEHPCPU1_LVC3_R3_SDA"$PHYS_NET_NAME"RST_PCIE_M2_N"CDS_PHYS_NET_NAME"SMB_PEHPCPU1_LVC3_R3_SDA";
63"PD_SMB_OCP2_HP_ADD1"$PHYS_NET_NAME"RST_PCIE_M2_N"CDS_PHYS_NET_NAME"PD_SMB_OCP1_HP_ADD1";
64"PD_SMB_OCP2_HP_ADD0"$PHYS_NET_NAME"RST_PCIE_M2_N"CDS_PHYS_NET_NAME"PD_SMB_OCP1_HP_ADD0";
65"SMB_PEHPCPU1_LVC3_SDA"$PHYS_NET_NAME"RST_PCIE_M2_N"CDS_PHYS_NET_NAME"SMB_PEHPCPU0_LVC3_SDA";
66"SMB_PEHPCPU1_LVC3_R3_SDA"$PHYS_NET_NAME"RST_PCIE_M2_N"CDS_PHYS_NET_NAME"SMB_PEHPCPU0_LVC3_R_SDA";
67"SMB_PEHPCPU1_LVC3_R3_SCL"$PHYS_NET_NAME"RST_PCIE_M2_N"CDS_PHYS_NET_NAME"SMB_PEHPCPU0_LVC3_R_SCL";
68"FM_SMB_PEHPCPU1_PCIE_ALERT_N"CDS_PHYS_NET_NAME"FM_SMB_PEHPCPU0_PCIE_ALERT_N";
69"SMB_PEHPCPU1_LVC3_R3_SCL"$PHYS_NET_NAME"RST_PCIE_M2_N"CDS_PHYS_NET_NAME"SMB_PEHPCPU1_LVC3_R3_SCL";
70"FM_SMB_CPU1_ALERT"CDS_PHYS_NET_NAME"FM_SMB_CPU0_ALERT";
71"OCP_V3_2_P3V3_PWRGD";
72"HP_OCP_V3_2_RST"$PHYS_NET_NAME"RST_PCIE_M2_N"CDS_PHYS_NET_NAME"HP_OCP_V3_1_RST";
73"HP_LVC3_OCP_V3_2_P12V_PWRGD"$PHYS_NET_NAME"RST_PCIE_M2_N"CDS_PHYS_NET_NAME"HP_LVC3_OCP_V3_1_P12V_PWRGD";
%"Q_RES"
"1","(-2200,1100)","0","pure_quanta","I100";
;
PART_NUMBER"CS03322FB03"
MATERIAL"CHIP"
VALUE"33.2"
PACK_TYPE"0402LF"
TOLERANCE"1%"
LOCATION"R4616"
CDS_LIB"pure_quanta"
WATTAGE"1/16W"
$SEC"1"
CDS_SEC"1";
"B"
$PN"2"29;
"A"
$PN"1"72;
%"Q_RES"
"1","(-550,-450)","0","pure_quanta","I103";
;
PART_NUMBER"CS03322FB03"
MATERIAL"CHIP"
VALUE"33.2"
TOLERANCE"1%"
PACK_TYPE"0402LF"
$LOCATION"R4755"
CDS_LIB"pure_quanta"
WATTAGE"1/16W"
CDS_LOCATION"R4755"
$SEC"1"
CDS_SEC"1";
"B"
$PN"2"43;
"A"
$PN"1"47;
%"Q_RES"
"1","(-550,-350)","0","pure_quanta","I104";
;
PART_NUMBER"CS03322FB03"
VALUE"33.2"
MATERIAL"CHIP"
PACK_TYPE"0402LF"
TOLERANCE"1%"
$LOCATION"R4754"
WATTAGE"1/16W"
CDS_LIB"pure_quanta"
CDS_LOCATION"R4754"
$SEC"1"
CDS_SEC"1";
"B"
$PN"2"42;
"A"
$PN"1"48;
%"Q_RES"
"2","(-275,0)","0","pure_quanta","I105";
;
PART_NUMBER"CS31002FB08"
VALUE"10K"
MATERIAL"CHIP"
WATTAGE"1/16W"
PACK_TYPE"0402LF"
TOLERANCE"1%"
$LOCATION"R4756"
CDS_LIB"pure_quanta"
CDS_LOCATION"R4756"
$SEC"1"
CDS_SEC"1";
"A"
$PN"1"10;
"B"
$PN"2"43;
%"UNIVERSAL_POWER"
"1","(-275,200)","0","logical_power","I106";
;
HDL_POWER"P3V3_AUX"
CDS_LIB"logical_power";
"A"10;
%"Q_RES"
"1","(1175,-825)","0","pure_quanta","I107";
;
PART_NUMBER"CS00002JB13"
MATERIAL"EMPTY"
TOLERANCE"5%"
PACK_TYPE"0402LF"
VALUE"0"
$LOCATION"R4758"
CDS_LIB"pure_quanta"
WATTAGE"1/16W"
CDS_LOCATION"R4758"
$SEC"1"
CDS_SEC"1";
"B"
$PN"2"44;
"A"
$PN"1"43;
%"74LVC1G08W57"
"1","(950,-450)","0","pure_quanta","I108";
;
PART_NUMBER"AL1G0008020"
PART_TYPE"SMLF"
VALUE"74LVC1G08W5-7"
MATERIAL"IC"
$LOCATION"U335"
CDS_LIB"pure_quanta"
NEEDS_NO_SIZE"TRUE"
CDS_LMAN_SYM_OUTLINE"-150,150,150,-150"
CDS_LOCATION"U335"
$SEC"1"
CDS_SEC"1";
"VCC"
$PN"5"11;
"Y"
$PN"4"44;
"GND"
$PN"3"26;
"B"
$PN"2"43;
"A"
$PN"1"42;
%"UNIVERSAL_GND"
"1","(1550,-425)","0","logical_power","I109";
;
HDL_POWER"GND"
CDS_LIB"logical_power";
"A"27;
%"Q_CAP"
"1","(1550,-200)","0","pure_quanta","I110";
;
PART_NUMBER"CH4104K1B00"
MATERIAL"X7R"
VALUE"0.1UF"
VOLTAGE"25V"
TOLERANCE"10%"
PACK_TYPE"0402"
$LOCATION"C2377"
CDS_LIB"pure_quanta"
CDS_LOCATION"C2377"
$SEC"1"
CDS_SEC"1";
"B"
$PN"2"27;
"A"
$PN"1"11;
%"Q_RES"
"1","(2175,-500)","0","pure_quanta","I111";
;
PART_NUMBER"CS04992FB07"
MATERIAL"CHIP"
VALUE"49.9"
$LOCATION"R4759"
WATTAGE"1/16W"
TOLERANCE"1%"
PACK_TYPE"0402LF"
CDS_LIB"pure_quanta"
CDS_LOCATION"R4759"
$SEC"1"
CDS_SEC"1";
"B"
$PN"2"50;
"A"
$PN"1"44;
%"Q_RES"
"1","(1125,250)","0","pure_quanta","I112";
;
PART_NUMBER"CS00002JB13"
PACK_TYPE"0402LF"
MATERIAL"EMPTY"
VALUE"0"
TOLERANCE"5%"
$LOCATION"R4757"
CDS_LIB"pure_quanta"
WATTAGE"1/16W"
CDS_LOCATION"R4757"
$SEC"1"
CDS_SEC"1";
"B"
$PN"2"44;
"A"
$PN"1"42;
%"UNIVERSAL_POWER"
"1","(1550,75)","0","logical_power","I113";
;
HDL_POWER"P3V3_AUX"
CDS_LIB"logical_power";
"A"11;
%"UNIVERSAL_GND"
"1","(600,-675)","0","logical_power","I116";
;
CDS_LIB"logical_power"
HDL_POWER"GND";
"A"26;
%"UNIVERSAL_POWER"
"1","(-800,3975)","0","logical_power","I118";
;
HDL_POWER"P3V3_AUX"
CDS_LIB"logical_power";
"A"1;
%"Q_RES"
"2","(-800,3750)","0","pure_quanta","I119";
;
PART_NUMBER"CS31002FB08"
MATERIAL"CHIP"
TOLERANCE"1%"
WATTAGE"1/16W"
PACK_TYPE"0402LF"
VALUE"10K"
$LOCATION"R4763"
CDS_LIB"pure_quanta"
CDS_LOCATION"R4763"
$SEC"1"
CDS_SEC"1";
"A"
$PN"1"1;
"B"
$PN"2"37;
%"UNIVERSAL_GND"
"1","(-2600,-875)","0","logical_power","I14";
;
HDL_POWER"GND"
CDS_LIB"logical_power";
"A"23;
%"Q_CAP"
"1","(-2600,-650)","0","pure_quanta","I15";
;
PART_NUMBER"CH4104K1B00"
VOLTAGE"25V"
MATERIAL"X7R"
VALUE"0.1UF"
TOLERANCE"10%"
PACK_TYPE"0402"
$LOCATION"C1818"
CDS_LIB"pure_quanta"
CDS_LOCATION"C1818"
$SEC"1"
CDS_SEC"1";
"B"
$PN"2"23;
"A"
$PN"1"8;
%"UNIVERSAL_POWER"
"1","(-2600,-375)","0","logical_power","I16";
;
HDL_POWER"P3V3_AUX"
CDS_LIB"logical_power";
"A"8;
%"Q_RES"
"1","(-3150,2075)","0","pure_quanta","I23";
;
PART_NUMBER"CS03322FB03"
PACK_TYPE"0402LF"
VALUE"33.2"
TOLERANCE"1%"
$LOCATION"R3158"
WATTAGE"1/16W"
MATERIAL"CHIP"
CDS_LIB"pure_quanta"
CDS_LOCATION"R3158"
$SEC"1"
CDS_SEC"1";
"B"
$PN"2"68;
"A"
$PN"1"70;
%"UNIVERSAL_GND"
"1","(-5175,2650)","0","logical_power","I24";
;
CDS_LIB"logical_power"
HDL_POWER"GND";
"A"16;
%"Q_RES"
"2","(-5175,2875)","0","pure_quanta","I25";
;
PART_NUMBER"CS21002FB06"
TOLERANCE"1%"
WATTAGE"1/16W"
MATERIAL"CHIP"
VALUE"1K"
PACK_TYPE"0402LF"
$LOCATION"R3150"
CDS_LIB"pure_quanta"
CDS_LOCATION"R3150"
$SEC"1"
CDS_SEC"1";
"A"
$PN"1"61;
"B"
$PN"2"16;
%"UNIVERSAL_GND"
"1","(-4925,2650)","0","logical_power","I26";
;
CDS_LIB"logical_power"
HDL_POWER"GND";
"A"17;
%"Q_RES"
"2","(-4925,2875)","0","pure_quanta","I27";
;
PART_NUMBER"CS21002FB06"
TOLERANCE"1%"
MATERIAL"CHIP"
VALUE"1K"
WATTAGE"1/16W"
PACK_TYPE"0402LF"
$LOCATION"R3152"
CDS_LIB"pure_quanta"
CDS_LOCATION"R3152"
$SEC"1"
CDS_SEC"1";
"A"
$PN"1"63;
"B"
$PN"2"17;
%"UNIVERSAL_GND"
"1","(-4675,2650)","0","logical_power","I28";
;
CDS_LIB"logical_power"
HDL_POWER"GND";
"A"18;
%"Q_RES"
"2","(-5175,3475)","0","pure_quanta","I29";
;
PART_NUMBER"CS21002FB06"
TOLERANCE"1%"
VALUE"1K"
WATTAGE"1/16W"
PACK_TYPE"0402LF"
MATERIAL"EMPTY"
$LOCATION"R3149"
CDS_LIB"pure_quanta"
CDS_LOCATION"R3149"
$SEC"1"
CDS_SEC"1";
"A"
$PN"1"5;
"B"
$PN"2"61;
%"MOSFET_N"
"1","(-4300,-1250)","0","pure_quanta","I3";
;
PART_NUMBER"BAM138K0000"
VALUE"BSS138K"
MATERIAL"IC"
$LOCATION"U215"
MANUF_PN"BSS138K"
CDS_LMAN_SYM_OUTLINE"-50,50,100,-150"
CDS_LIB"pure_quanta"
PACK_TYPE"SMLF"
CDS_LOCATION"U215"
$SEC"1"
CDS_SEC"1";
"GATE"
$PN"G"51;
"SOURCE"
$PN"S"25;
"DRAIN"
$PN"D"54;
%"UNIVERSAL_POWER"
"1","(-5175,3875)","0","logical_power","I30";
;
HDL_POWER"P3V3_AUX"
CDS_LIB"logical_power";
"A"5;
%"Q_RES"
"2","(-4925,3475)","0","pure_quanta","I31";
;
PART_NUMBER"CS21002FB06"
VALUE"1K"
TOLERANCE"1%"
WATTAGE"1/16W"
MATERIAL"EMPTY"
PACK_TYPE"0402LF"
$LOCATION"R3151"
CDS_LIB"pure_quanta"
CDS_LOCATION"R3151"
$SEC"1"
CDS_SEC"1";
"A"
$PN"1"5;
"B"
$PN"2"63;
%"Q_RES"
"2","(-4675,3475)","0","pure_quanta","I32";
;
PART_NUMBER"CS21002FB06"
WATTAGE"1/16W"
TOLERANCE"1%"
VALUE"1K"
MATERIAL"EMPTY"
PACK_TYPE"0402LF"
$LOCATION"R3153"
CDS_LIB"pure_quanta"
CDS_LOCATION"R3153"
$SEC"1"
CDS_SEC"1";
"A"
$PN"1"5;
"B"
$PN"2"64;
%"Q_RES"
"1","(-3150,2125)","0","pure_quanta","I33";
;
PART_NUMBER"CS03322FB03"
PACK_TYPE"0402LF"
VALUE"33.2"
TOLERANCE"1%"
$LOCATION"R3157"
CDS_LIB"pure_quanta"
WATTAGE"1/16W"
MATERIAL"CHIP"
CDS_LOCATION"R3157"
$SEC"1"
CDS_SEC"1";
"B"
$PN"2"66;
"A"
$PN"1"65;
%"Q_RES"
"1","(-3150,2175)","0","pure_quanta","I34";
;
PART_NUMBER"CS03322FB03"
WATTAGE"1/16W"
VALUE"33.2"
PACK_TYPE"0402LF"
TOLERANCE"1%"
MATERIAL"CHIP"
$LOCATION"R3156"
CDS_LIB"pure_quanta"
CDS_LOCATION"R3156"
$SEC"1"
CDS_SEC"1";
"B"
$PN"2"67;
"A"
$PN"1"55;
%"UNIVERSAL_GND"
"1","(-2825,3550)","0","logical_power","I38";
;
HDL_POWER"GND"
CDS_LIB"logical_power";
"A"19;
%"Q_CAP"
"1","(-2825,3775)","0","pure_quanta","I39";
;
PART_NUMBER"CH4104K1B00"
TOLERANCE"10%"
MATERIAL"X7R"
VOLTAGE"25V"
VALUE"0.1UF"
PACK_TYPE"0402"
$LOCATION"C1817"
CDS_LIB"pure_quanta"
CDS_LOCATION"C1817"
$SEC"1"
CDS_SEC"1";
"B"
$PN"2"19;
"A"
$PN"1"6;
%"UNIVERSAL_GND"
"1","(-4250,-1625)","0","logical_power","I4";
;
HDL_POWER"GND"
CDS_LIB"logical_power";
"A"25;
%"UNIVERSAL_POWER"
"1","(-2825,4050)","0","logical_power","I40";
;
HDL_POWER"P3V3_AUX"
CDS_LIB"logical_power";
"A"6;
%"UNIVERSAL_GND"
"1","(-2250,2500)","0","logical_power","I41";
;
CDS_LIB"logical_power"
HDL_POWER"GND";
"A"21;
%"UNIVERSAL_GND"
"1","(-3475,-1250)","0","logical_power","I5";
;
HDL_POWER"GND"
CDS_LIB"logical_power";
"A"24;
%"UNIVERSAL_GND"
"1","(1725,625)","0","logical_power","I55";
;
HDL_POWER"GND"
CDS_LIB"logical_power";
"A"22;
%"74LVC1G08W57"
"1","(2075,850)","0","pure_quanta","I56";
;
PART_NUMBER"AL1G0008020"
VALUE"74LVC1G08W5-7"
MATERIAL"IC"
PART_TYPE"SMLF"
LOCATION"U53"
CDS_LMAN_SYM_OUTLINE"-150,150,150,-150"
NEEDS_NO_SIZE"TRUE"
CDS_LIB"pure_quanta"
$SEC"1"
CDS_SEC"1";
"VCC"
$PN"5"7;
"Y"
$PN"4"49;
"GND"
$PN"3"22;
"B"
$PN"2"46;
"A"
$PN"1"45;
%"UNIVERSAL_GND"
"1","(2625,1125)","0","logical_power","I57";
;
HDL_POWER"GND"
CDS_LIB"logical_power";
"A"20;
%"Q_CAP"
"1","(2625,1350)","0","pure_quanta","I58";
;
PART_NUMBER"CH4104K1B00"
MATERIAL"X7R"
TOLERANCE"10%"
VOLTAGE"25V"
VALUE"0.1UF"
PACK_TYPE"0402"
$LOCATION"C1820"
CDS_LIB"pure_quanta"
CDS_LOCATION"C1820"
$SEC"1"
CDS_SEC"1";
"B"
$PN"2"20;
"A"
$PN"1"7;
%"UNIVERSAL_POWER"
"1","(2625,1625)","0","logical_power","I59";
;
HDL_POWER"P3V3_AUX"
CDS_LIB"logical_power";
"A"7;
%"Q_RES"
"2","(-4675,2875)","0","pure_quanta","I65";
;
PART_NUMBER"CS21002FB06"
TOLERANCE"1%"
MATERIAL"CHIP"
WATTAGE"1/16W"
VALUE"1K"
PACK_TYPE"0402LF"
$LOCATION"R3154"
CDS_LIB"pure_quanta"
CDS_LOCATION"R3154"
$SEC"1"
CDS_SEC"1";
"A"
$PN"1"64;
"B"
$PN"2"18;
%"PCA9555APW"
"1","(-1775,3125)","0","pure_quanta","I66";
;
PART_NUMBER"AL009555K07"
PART_TYPE"SMLF"
MATERIAL"IC"
VALUE"PCA9555APW"
LOCATION"U51"
CDS_LIB"pure_quanta"
CDS_LMAN_SYM_OUTLINE"-225,500,225,-500"
NEEDS_NO_SIZE"TRUE"
$SEC"1"
CDS_SEC"1";
"A2"
$PN"3"61;
"A1"
$PN"2"63;
"A0"
$PN"21"64;
"P1_7"
$PN"20"30;
"P1_6"
$PN"19"31;
"P1_5"
$PN"18"32;
"P1_4"
$PN"17"33;
"P1_3"
$PN"16"34;
"P1_2"
$PN"15"35;
"P1_1"
$PN"14"36;
"P1_0"
$PN"13"56;
"P0_7"
$PN"11"57;
"P0_6"
$PN"10"58;
"P0_5"
$PN"9"59;
"P0_4"
$PN"8"41;
"P0_3"
$PN"7"40;
"P0_2"
$PN"6"37;
"P0_1"
$PN"5"39;
"P0_0"
$PN"4"38;
"SCL"
$PN"22"69;
"SDA"
$PN"23"62;
"INT# \B"
$PN"1"60;
"VSS"
$PN"12"21;
"VDD"
$PN"24"6;
%"Q_RES"
"2","(-4250,-700)","0","pure_quanta","I7";
;
PART_NUMBER"CS21002FB06"
WATTAGE"1/16W"
TOLERANCE"1%"
MATERIAL"CHIP"
PACK_TYPE"0402LF"
VALUE"1K"
$LOCATION"R3155"
CDS_LIB"pure_quanta"
CDS_LOCATION"R3155"
$SEC"1"
CDS_SEC"1";
"A"
$PN"1"9;
"B"
$PN"2"54;
%"UNIVERSAL_POWER"
"1","(-4250,-425)","0","logical_power","I8";
;
HDL_POWER"P3V3_AUX"
CDS_LIB"logical_power";
"A"9;
%"UNIVERSAL_GND"
"1","(-4500,800)","0","logical_power","I81";
;
HDL_POWER"GND"
CDS_LIB"logical_power";
"A"15;
%"UNIVERSAL_GND"
"1","(-3300,1175)","0","logical_power","I84";
;
HDL_POWER"GND"
CDS_LIB"logical_power";
"A"14;
%"APX80929SAG7"
"1","(-3800,1200)","2","pure_quanta","I85";
;
PART_NUMBER"AL080929000"
VALUE"APX809-29SAG-7"
PART_TYPE"SMLF"
MATERIAL"IC"
$LOCATION"U216"
CDS_LMAN_SYM_OUTLINE"-225,200,225,-200"
NEEDS_NO_SIZE"TRUE"
CDS_LIB"pure_quanta"
CDS_LOCATION"U216"
$SEC"1"
CDS_SEC"1";
"GND"
$PN"1"14;
"RESET_L \B"
$PN"2"72;
"VCC"
$PN"3"2;
%"UNIVERSAL_POWER"
"1","(-4500,1350)","0","logical_power","I86";
;
HDL_POWER"P3V3_OCP_V3_2"
CDS_LIB"logical_power";
"A"2;
%"Q_CAP"
"1","(-4500,1025)","2","pure_quanta","I87";
;
PART_NUMBER"CH4104K1B00"
MATERIAL"X7R"
VOLTAGE"25V"
VALUE"0.1UF"
PACK_TYPE"0402"
TOLERANCE"10%"
$LOCATION"C1819"
CDS_LIB"pure_quanta"
CDS_LOCATION"C1819"
$SEC"1"
CDS_SEC"1";
"B"
$PN"2"15;
"A"
$PN"1"2;
%"UNIVERSAL_POWER"
"1","(100,1775)","0","logical_power","I89";
;
HDL_POWER"P3V3_AUX"
CDS_LIB"logical_power";
"A"4;
%"74LVC1G08W57"
"1","(-3175,-1025)","0","pure_quanta","I9";
;
PART_NUMBER"AL1G0008020"
VALUE"74LVC1G08W5-7"
PART_TYPE"SMLF"
MATERIAL"IC"
LOCATION"U50"
NEEDS_NO_SIZE"TRUE"
CDS_LMAN_SYM_OUTLINE"-150,150,150,-150"
CDS_LIB"pure_quanta"
$SEC"1"
CDS_SEC"1";
"VCC"
$PN"5"8;
"Y"
$PN"4"53;
"GND"
$PN"3"24;
"B"
$PN"2"54;
"A"
$PN"1"52;
%"Q_CAP"
"1","(100,1500)","0","pure_quanta","I90";
;
PART_NUMBER"CH4104K1B00"
VALUE"0.1UF"
VOLTAGE"25V"
PACK_TYPE"0402"
TOLERANCE"10%"
MATERIAL"X7R"
$LOCATION"C2347"
CDS_LIB"pure_quanta"
CDS_LOCATION"C2347"
$SEC"1"
CDS_SEC"1";
"B"
$PN"2"12;
"A"
$PN"1"4;
%"UNIVERSAL_GND"
"1","(100,1275)","0","logical_power","I91";
;
CDS_LIB"logical_power"
HDL_POWER"GND";
"A"12;
%"74LVC1G08W57"
"1","(-450,1000)","0","pure_quanta","I92";
;
PART_NUMBER"AL1G0008020"
MATERIAL"IC"
PART_TYPE"SMLF"
VALUE"74LVC1G08W5-7"
$LOCATION"U323"
CDS_LIB"pure_quanta"
NEEDS_NO_SIZE"TRUE"
CDS_LMAN_SYM_OUTLINE"-150,150,150,-150"
CDS_LOCATION"U323"
$SEC"1"
CDS_SEC"1";
"VCC"
$PN"5"4;
"Y"
$PN"4"28;
"GND"
$PN"3"13;
"B"
$PN"2"73;
"A"
$PN"1"29;
%"UNIVERSAL_GND"
"1","(-800,775)","0","logical_power","I93";
;
CDS_LIB"logical_power"
HDL_POWER"GND";
"A"13;
%"UNIVERSAL_POWER"
"1","(-1650,1875)","0","logical_power","I94";
;
HDL_POWER"P3V3_AUX"
CDS_LIB"logical_power";
"A"3;
%"Q_RES"
"2","(-1650,1675)","0","pure_quanta","I95";
;
PART_NUMBER"CS21002FB06"
VALUE"1K"
PACK_TYPE"0402LF"
MATERIAL"EMPTY"
TOLERANCE"1%"
WATTAGE"1/16W"
LOCATION"R1132"
CDS_LIB"pure_quanta"
$SEC"1"
CDS_SEC"1";
"A"
$PN"1"3;
"B"
$PN"2"29;
%"Q_RES"
"1","(-2225,1425)","0","pure_quanta","I96";
;
PART_NUMBER"CS00002JB13"
VALUE"0"
MATERIAL"EMPTY"
TOLERANCE"5%"
PACK_TYPE"0402LF"
$LOCATION"R4615"
CDS_LIB"pure_quanta"
WATTAGE"1/16W"
CDS_LOCATION"R4615"
$SEC"1"
CDS_SEC"1";
"B"
$PN"2"29;
"A"
$PN"1"71;
%"Q_RES"
"1","(775,950)","0","pure_quanta","I99";
;
PART_NUMBER"CS03322FB03"
VALUE"33.2"
TOLERANCE"1%"
PACK_TYPE"0402LF"
$LOCATION"R4617"
MATERIAL"CHIP"
WATTAGE"1/16W"
CDS_LIB"pure_quanta"
CDS_LOCATION"R4617"
$SEC"1"
CDS_SEC"1";
"B"
$PN"2"45;
"A"
$PN"1"28;
END.
